(kicad_pcb
	(version 20260206)
	(generator "pcbnew")
	(generator_version "10.0")
	(general
		(thickness 1.6)
		(legacy_teardrops no)
	)
	(paper "A4")
	(title_block
		(title "panther-plus-userver — 13130-1b_20150205.brd")
		(comment 1 "Honey Badger (Wiwynn) / footprints 1242-1249 of 1509")
	)
	(layers
		(0 "F.Cu" signal "TOP")
		(4 "In1.Cu" signal "L2")
		(6 "In2.Cu" signal "L3")
		(8 "In3.Cu" signal "L4")
		(10 "In4.Cu" signal "L5")
		(12 "In5.Cu" signal "L6")
		(14 "In6.Cu" signal "L7")
		(16 "In7.Cu" signal "L8")
		(18 "In8.Cu" signal "L9")
		(20 "In9.Cu" signal "L10")
		(22 "In10.Cu" signal "L11")
		(2 "B.Cu" signal "BOTTOM")
		(9 "F.Adhes" user "F.Adhesive")
		(11 "B.Adhes" user "B.Adhesive")
		(13 "F.Paste" user "Package Geometry/Pastemask Top")
		(15 "B.Paste" user "Package Geometry/Pastemask Bottom")
		(5 "F.SilkS" user "Ref Des/Silkscreen Top")
		(7 "B.SilkS" user "Ref Des/Silkscreen Bottom")
		(1 "F.Mask" user "Board Geometry/Soldermask Top")
		(3 "B.Mask" user "Board Geometry/Soldermask Bottom")
		(17 "Dwgs.User" user "User.Drawings")
		(19 "Cmts.User" user "User.Comments")
		(21 "Eco1.User" user "User.Eco1")
		(23 "Eco2.User" user "User.Eco2")
		(25 "Edge.Cuts" user "Board Geometry/Outline")
		(27 "Margin" user)
		(31 "F.CrtYd" user "Package Geometry/Place Bound Top")
		(29 "B.CrtYd" user "Package Geometry/Place Bound Bottom")
		(35 "F.Fab" user "Ref Des/Assembly Top")
		(33 "B.Fab" user "Ref Des/Assembly Bottom")
	)
	(footprint ""
		(layer "B.Cu")
		(at 37.719 -23.495 -90)
		(property "Reference" "R349"
			(at 0 0 90)
			(layer "B.SilkS")
			(hide yes)
			(effects
				(font
					(size 1.27 1.27)
				)
				(justify mirror)
			)
		)
		(property "Value" "33R2F-3-GP"
			(at -0.064008 -3.993896 270)
			(unlocked yes)
			(layer "B.Fab")
			(hide yes)
			(effects
				(font
					(size 1.016 1.016)
					(thickness 0.1524)
				)
				(justify mirror)
			)
		)
		(property "Device Type" "R402H16"
			(at -0.064008 -5.517896 270)
			(unlocked yes)
			(layer "B.Fab")
			(hide yes)
			(effects
				(font
					(size 1.016 1.016)
					(thickness 0.1524)
				)
				(justify mirror)
			)
		)
		(duplicate_pad_numbers_are_jumpers no)
		(fp_rect
			(start 0.381 0.8382)
			(end -0.381 -0.8382)
			(stroke
				(width 0)
				(type default)
			)
			(fill no)
			(layer "B.CrtYd")
		)
		(fp_rect
			(start 0.381 0.8382)
			(end -0.381 -0.8382)
			(stroke
				(width 0)
				(type default)
			)
			(fill no)
			(layer "B.Fab")
		)
		(pad "1" smd custom
			(at 0 -0.4318 90)
			(size 0.127 0.127)
			(layers "B.Cu" "B.Mask" "B.Paste")
			(net "CLK_100M_CLKBUFF_NGFF_R_DP")
			(options
				(clearance outline)
				(anchor circle)
			)
			(primitives
				(gr_poly
					(pts
						(arc
							(start -0.2032 0.2794)
							(mid -0.239121 0.264521)
							(end -0.254 0.2286)
						)
						(arc
							(start -0.254 -0.2286)
							(mid -0.239121 -0.264521)
							(end -0.2032 -0.2794)
						)
						(arc
							(start 0.2032 -0.2794)
							(mid 0.239121 -0.264521)
							(end 0.254 -0.2286)
						)
						(arc
							(start 0.254 0.2286)
							(mid 0.239121 0.264521)
							(end 0.2032 0.2794)
						)
					)
					(width 0)
					(fill yes)
				)
			)
		)
		(pad "2" smd custom
			(at 0 0.4318 90)
			(size 0.127 0.127)
			(layers "B.Cu" "B.Mask" "B.Paste")
			(net "CLK_100M_CLKBUFF_NGFF_DP")
			(options
				(clearance outline)
				(anchor circle)
			)
			(primitives
				(gr_poly
					(pts
						(arc
							(start -0.2032 0.2794)
							(mid -0.239121 0.264521)
							(end -0.254 0.2286)
						)
						(arc
							(start -0.254 -0.2286)
							(mid -0.239121 -0.264521)
							(end -0.2032 -0.2794)
						)
						(arc
							(start 0.2032 -0.2794)
							(mid 0.239121 -0.264521)
							(end 0.254 -0.2286)
						)
						(arc
							(start 0.254 0.2286)
							(mid 0.239121 0.264521)
							(end 0.2032 0.2794)
						)
					)
					(width 0)
					(fill yes)
				)
			)
		)
	)
	(footprint ""
		(layer "B.Cu")
		(at 107.442 -52.721002 180)
		(property "Reference" "C127"
			(at 0 0 0)
			(layer "B.SilkS")
			(hide yes)
			(effects
				(font
					(size 1.27 1.27)
				)
				(justify mirror)
			)
		)
		(property "Value" "SCD1U16V2KX-3GP"
			(at -1.1811 -2.7051 180)
			(unlocked yes)
			(layer "B.Fab")
			(hide yes)
			(effects
				(font
					(size 1.016 1.016)
					(thickness 0.1524)
				)
				(justify mirror)
			)
		)
		(property "Device Type" "C402H22"
			(at -1.1811 -4.2291 180)
			(unlocked yes)
			(layer "B.Fab")
			(hide yes)
			(effects
				(font
					(size 1.016 1.016)
					(thickness 0.1524)
				)
				(justify mirror)
			)
		)
		(duplicate_pad_numbers_are_jumpers no)
		(fp_rect
			(start 0.381 0.7366)
			(end -0.381 -0.7366)
			(stroke
				(width 0)
				(type default)
			)
			(fill no)
			(layer "B.CrtYd")
		)
		(fp_rect
			(start 0.381 0.7366)
			(end -0.381 -0.7366)
			(stroke
				(width 0)
				(type default)
			)
			(fill no)
			(layer "B.Fab")
		)
		(pad "1" smd custom
			(at 0 -0.4572)
			(size 0.1143 0.1143)
			(layers "B.Cu" "B.Mask" "B.Paste")
			(net "PV_VDDR")
			(options
				(clearance outline)
				(anchor circle)
			)
			(primitives
				(gr_poly
					(pts
						(arc
							(start -0.254 0.1778)
							(mid -0.239121 0.213721)
							(end -0.2032 0.2286)
						)
						(arc
							(start 0.2032 0.2286)
							(mid 0.239121 0.213721)
							(end 0.254 0.1778)
						)
						(arc
							(start 0.254 -0.1778)
							(mid 0.239121 -0.213721)
							(end 0.2032 -0.2286)
						)
						(arc
							(start -0.2032 -0.2286)
							(mid -0.239121 -0.213721)
							(end -0.254 -0.1778)
						)
					)
					(width 0)
					(fill yes)
				)
			)
		)
		(pad "2" smd custom
			(at 0 0.4572)
			(size 0.1143 0.1143)
			(layers "B.Cu" "B.Mask" "B.Paste")
			(net "GND")
			(options
				(clearance outline)
				(anchor circle)
			)
			(primitives
				(gr_poly
					(pts
						(arc
							(start -0.254 0.1778)
							(mid -0.239121 0.213721)
							(end -0.2032 0.2286)
						)
						(arc
							(start 0.2032 0.2286)
							(mid 0.239121 0.213721)
							(end 0.254 0.1778)
						)
						(arc
							(start 0.254 -0.1778)
							(mid 0.239121 -0.213721)
							(end 0.2032 -0.2286)
						)
						(arc
							(start -0.2032 -0.2286)
							(mid -0.239121 -0.213721)
							(end -0.254 -0.1778)
						)
					)
					(width 0)
					(fill yes)
				)
			)
		)
	)
	(footprint ""
		(layer "B.Cu")
		(at 88.392 -46.228)
		(property "Reference" "R296"
			(at 0 0 0)
			(layer "B.SilkS")
			(hide yes)
			(effects
				(font
					(size 1.27 1.27)
				)
				(justify mirror)
			)
		)
		(property "Value" "10KR2F-2-GP"
			(at -0.064008 -3.993896 0)
			(unlocked yes)
			(layer "B.Fab")
			(hide yes)
			(effects
				(font
					(size 1.016 1.016)
					(thickness 0.1524)
				)
				(justify mirror)
			)
		)
		(property "Device Type" "R402H16"
			(at -0.064008 -5.517896 0)
			(unlocked yes)
			(layer "B.Fab")
			(hide yes)
			(effects
				(font
					(size 1.016 1.016)
					(thickness 0.1524)
				)
				(justify mirror)
			)
		)
		(duplicate_pad_numbers_are_jumpers no)
		(fp_rect
			(start 0.381 0.8382)
			(end -0.381 -0.8382)
			(stroke
				(width 0)
				(type default)
			)
			(fill no)
			(layer "B.CrtYd")
		)
		(fp_rect
			(start 0.381 0.8382)
			(end -0.381 -0.8382)
			(stroke
				(width 0)
				(type default)
			)
			(fill no)
			(layer "B.Fab")
		)
		(pad "1" smd custom
			(at 0 -0.4318 180)
			(size 0.127 0.127)
			(layers "B.Cu" "B.Mask" "B.Paste")
			(net "P3V3")
			(options
				(clearance outline)
				(anchor circle)
			)
			(primitives
				(gr_poly
					(pts
						(arc
							(start -0.2032 0.2794)
							(mid -0.239121 0.264521)
							(end -0.254 0.2286)
						)
						(arc
							(start -0.254 -0.2286)
							(mid -0.239121 -0.264521)
							(end -0.2032 -0.2794)
						)
						(arc
							(start 0.2032 -0.2794)
							(mid 0.239121 -0.264521)
							(end 0.254 -0.2286)
						)
						(arc
							(start 0.254 0.2286)
							(mid 0.239121 0.264521)
							(end 0.2032 0.2794)
						)
					)
					(width 0)
					(fill yes)
				)
			)
		)
		(pad "2" smd custom
			(at 0 0.4318 180)
			(size 0.127 0.127)
			(layers "B.Cu" "B.Mask" "B.Paste")
			(net "IRQ_CPU_SERIAL")
			(options
				(clearance outline)
				(anchor circle)
			)
			(primitives
				(gr_poly
					(pts
						(arc
							(start -0.2032 0.2794)
							(mid -0.239121 0.264521)
							(end -0.254 0.2286)
						)
						(arc
							(start -0.254 -0.2286)
							(mid -0.239121 -0.264521)
							(end -0.2032 -0.2794)
						)
						(arc
							(start 0.2032 -0.2794)
							(mid 0.239121 -0.264521)
							(end 0.254 -0.2286)
						)
						(arc
							(start 0.254 0.2286)
							(mid 0.239121 0.264521)
							(end 0.2032 0.2794)
						)
					)
					(width 0)
					(fill yes)
				)
			)
		)
	)
	(footprint ""
		(layer "B.Cu")
		(at 69.596 -46.863 180)
		(property "Reference" "R300"
			(at 0 0 0)
			(layer "B.SilkS")
			(hide yes)
			(effects
				(font
					(size 1.27 1.27)
				)
				(justify mirror)
			)
		)
		(property "Value" "0R2J-2-GP"
			(at -0.064008 -3.993896 180)
			(unlocked yes)
			(layer "B.Fab")
			(hide yes)
			(effects
				(font
					(size 1.016 1.016)
					(thickness 0.1524)
				)
				(justify mirror)
			)
		)
		(property "Device Type" "R402H16"
			(at -0.064008 -5.517896 180)
			(unlocked yes)
			(layer "B.Fab")
			(hide yes)
			(effects
				(font
					(size 1.016 1.016)
					(thickness 0.1524)
				)
				(justify mirror)
			)
		)
		(duplicate_pad_numbers_are_jumpers no)
		(fp_rect
			(start 0.381 0.8382)
			(end -0.381 -0.8382)
			(stroke
				(width 0)
				(type default)
			)
			(fill no)
			(layer "B.CrtYd")
		)
		(fp_rect
			(start 0.381 0.8382)
			(end -0.381 -0.8382)
			(stroke
				(width 0)
				(type default)
			)
			(fill no)
			(layer "B.Fab")
		)
		(pad "1" smd custom
			(at 0 -0.4318)
			(size 0.127 0.127)
			(layers "B.Cu" "B.Mask" "B.Paste")
			(net "IRQ_NMI_R")
			(options
				(clearance outline)
				(anchor circle)
			)
			(primitives
				(gr_poly
					(pts
						(arc
							(start -0.2032 0.2794)
							(mid -0.239121 0.264521)
							(end -0.254 0.2286)
						)
						(arc
							(start -0.254 -0.2286)
							(mid -0.239121 -0.264521)
							(end -0.2032 -0.2794)
						)
						(arc
							(start 0.2032 -0.2794)
							(mid 0.239121 -0.264521)
							(end 0.254 -0.2286)
						)
						(arc
							(start 0.254 0.2286)
							(mid 0.239121 0.264521)
							(end 0.2032 0.2794)
						)
					)
					(width 0)
					(fill yes)
				)
			)
		)
		(pad "2" smd custom
			(at 0 0.4318)
			(size 0.127 0.127)
			(layers "B.Cu" "B.Mask" "B.Paste")
			(net "IRQ_NMI")
			(options
				(clearance outline)
				(anchor circle)
			)
			(primitives
				(gr_poly
					(pts
						(arc
							(start -0.2032 0.2794)
							(mid -0.239121 0.264521)
							(end -0.254 0.2286)
						)
						(arc
							(start -0.254 -0.2286)
							(mid -0.239121 -0.264521)
							(end -0.2032 -0.2794)
						)
						(arc
							(start 0.2032 -0.2794)
							(mid 0.239121 -0.264521)
							(end 0.254 -0.2286)
						)
						(arc
							(start 0.254 0.2286)
							(mid 0.239121 0.264521)
							(end 0.2032 0.2794)
						)
					)
					(width 0)
					(fill yes)
				)
			)
		)
	)
	(footprint ""
		(layer "B.Cu")
		(at 53.467 -18.796 -90)
		(property "Reference" "C303"
			(at 0 0 90)
			(layer "B.SilkS")
			(hide yes)
			(effects
				(font
					(size 1.27 1.27)
				)
				(justify mirror)
			)
		)
		(property "Value" "SCD1U16V2KX-3GP"
			(at -1.8923 -1.2065 270)
			(unlocked yes)
			(layer "B.Fab")
			(hide yes)
			(effects
				(font
					(size 1.016 1.016)
					(thickness 0.1524)
				)
				(justify mirror)
			)
		)
		(property "Device Type" "C402H22"
			(at -1.8923 -2.7305 270)
			(unlocked yes)
			(layer "B.Fab")
			(hide yes)
			(effects
				(font
					(size 1.016 1.016)
					(thickness 0.1524)
				)
				(justify mirror)
			)
		)
		(duplicate_pad_numbers_are_jumpers no)
		(fp_rect
			(start 0.381 0.7366)
			(end -0.381 -0.7366)
			(stroke
				(width 0)
				(type default)
			)
			(fill no)
			(layer "B.CrtYd")
		)
		(fp_rect
			(start 0.381 0.7366)
			(end -0.381 -0.7366)
			(stroke
				(width 0)
				(type default)
			)
			(fill no)
			(layer "B.Fab")
		)
		(pad "1" smd custom
			(at 0 -0.4572 90)
			(size 0.1143 0.1143)
			(layers "B.Cu" "B.Mask" "B.Paste")
			(net "P3V3")
			(options
				(clearance outline)
				(anchor circle)
			)
			(primitives
				(gr_poly
					(pts
						(arc
							(start -0.254 0.1778)
							(mid -0.239121 0.213721)
							(end -0.2032 0.2286)
						)
						(arc
							(start 0.2032 0.2286)
							(mid 0.239121 0.213721)
							(end 0.254 0.1778)
						)
						(arc
							(start 0.254 -0.1778)
							(mid 0.239121 -0.213721)
							(end 0.2032 -0.2286)
						)
						(arc
							(start -0.2032 -0.2286)
							(mid -0.239121 -0.213721)
							(end -0.254 -0.1778)
						)
					)
					(width 0)
					(fill yes)
				)
			)
		)
		(pad "2" smd custom
			(at 0 0.4572 90)
			(size 0.1143 0.1143)
			(layers "B.Cu" "B.Mask" "B.Paste")
			(net "GND")
			(options
				(clearance outline)
				(anchor circle)
			)
			(primitives
				(gr_poly
					(pts
						(arc
							(start -0.254 0.1778)
							(mid -0.239121 0.213721)
							(end -0.2032 0.2286)
						)
						(arc
							(start 0.2032 0.2286)
							(mid 0.239121 0.213721)
							(end 0.254 0.1778)
						)
						(arc
							(start 0.254 -0.1778)
							(mid 0.239121 -0.213721)
							(end 0.2032 -0.2286)
						)
						(arc
							(start -0.2032 -0.2286)
							(mid -0.239121 -0.213721)
							(end -0.254 -0.1778)
						)
					)
					(width 0)
					(fill yes)
				)
			)
		)
	)
	(footprint ""
		(layer "B.Cu")
		(at 23.5712 -56.642 180)
		(property "Reference" "PR66"
			(at 0 0 0)
			(layer "B.SilkS")
			(hide yes)
			(effects
				(font
					(size 1.27 1.27)
				)
				(justify mirror)
			)
		)
		(property "Value" "7K87R2F-GP"
			(at -1.7907 -1.1176 180)
			(unlocked yes)
			(layer "B.Fab")
			(hide yes)
			(effects
				(font
					(size 1.016 1.016)
					(thickness 0.1524)
				)
				(justify mirror)
			)
		)
		(property "Device Type" "R402H16"
			(at -1.7907 -2.6416 180)
			(unlocked yes)
			(layer "B.Fab")
			(hide yes)
			(effects
				(font
					(size 1.016 1.016)
					(thickness 0.1524)
				)
				(justify mirror)
			)
		)
		(duplicate_pad_numbers_are_jumpers no)
		(fp_rect
			(start 0.381 0.8382)
			(end -0.381 -0.8382)
			(stroke
				(width 0)
				(type default)
			)
			(fill no)
			(layer "B.CrtYd")
		)
		(fp_rect
			(start 0.381 0.8382)
			(end -0.381 -0.8382)
			(stroke
				(width 0)
				(type default)
			)
			(fill no)
			(layer "B.Fab")
		)
		(pad "1" smd custom
			(at 0 -0.4318)
			(size 0.127 0.127)
			(layers "B.Cu" "B.Mask" "B.Paste")
			(net "VR_PVCCP_PROG1")
			(options
				(clearance outline)
				(anchor circle)
			)
			(primitives
				(gr_poly
					(pts
						(arc
							(start -0.2032 0.2794)
							(mid -0.239121 0.264521)
							(end -0.254 0.2286)
						)
						(arc
							(start -0.254 -0.2286)
							(mid -0.239121 -0.264521)
							(end -0.2032 -0.2794)
						)
						(arc
							(start 0.2032 -0.2794)
							(mid 0.239121 -0.264521)
							(end 0.254 -0.2286)
						)
						(arc
							(start 0.254 0.2286)
							(mid 0.239121 0.264521)
							(end 0.2032 0.2794)
						)
					)
					(width 0)
					(fill yes)
				)
			)
		)
		(pad "2" smd custom
			(at 0 0.4318)
			(size 0.127 0.127)
			(layers "B.Cu" "B.Mask" "B.Paste")
			(net "GND")
			(options
				(clearance outline)
				(anchor circle)
			)
			(primitives
				(gr_poly
					(pts
						(arc
							(start -0.2032 0.2794)
							(mid -0.239121 0.264521)
							(end -0.254 0.2286)
						)
						(arc
							(start -0.254 -0.2286)
							(mid -0.239121 -0.264521)
							(end -0.2032 -0.2794)
						)
						(arc
							(start 0.2032 -0.2794)
							(mid 0.239121 -0.264521)
							(end 0.254 -0.2286)
						)
						(arc
							(start 0.254 0.2286)
							(mid 0.239121 0.264521)
							(end 0.2032 0.2794)
						)
					)
					(width 0)
					(fill yes)
				)
			)
		)
	)
	(footprint ""
		(layer "B.Cu")
		(at 16.764 -35.179 90)
		(property "Reference" "PR190"
			(at 0 0 90)
			(layer "B.SilkS")
			(hide yes)
			(effects
				(font
					(size 1.27 1.27)
				)
				(justify mirror)
			)
		)
		(property "Value" "0R2J-2-GP"
			(at -1.7907 -1.1176 90)
			(unlocked yes)
			(layer "B.Fab")
			(hide yes)
			(effects
				(font
					(size 1.016 1.016)
					(thickness 0.1524)
				)
				(justify mirror)
			)
		)
		(property "Device Type" "R402H16"
			(at -1.7907 -2.6416 90)
			(unlocked yes)
			(layer "B.Fab")
			(hide yes)
			(effects
				(font
					(size 1.016 1.016)
					(thickness 0.1524)
				)
				(justify mirror)
			)
		)
		(duplicate_pad_numbers_are_jumpers no)
		(fp_rect
			(start 0.381 0.8382)
			(end -0.381 -0.8382)
			(stroke
				(width 0)
				(type default)
			)
			(fill no)
			(layer "B.CrtYd")
		)
		(fp_rect
			(start 0.381 0.8382)
			(end -0.381 -0.8382)
			(stroke
				(width 0)
				(type default)
			)
			(fill no)
			(layer "B.Fab")
		)
		(pad "1" smd custom
			(at 0 -0.4318 270)
			(size 0.127 0.127)
			(layers "B.Cu" "B.Mask" "B.Paste")
			(net "P3V3_STBY_ROVP")
			(options
				(clearance outline)
				(anchor circle)
			)
			(primitives
				(gr_poly
					(pts
						(arc
							(start -0.2032 0.2794)
							(mid -0.239121 0.264521)
							(end -0.254 0.2286)
						)
						(arc
							(start -0.254 -0.2286)
							(mid -0.239121 -0.264521)
							(end -0.2032 -0.2794)
						)
						(arc
							(start 0.2032 -0.2794)
							(mid 0.239121 -0.264521)
							(end 0.254 -0.2286)
						)
						(arc
							(start 0.254 0.2286)
							(mid 0.239121 0.264521)
							(end 0.2032 0.2794)
						)
					)
					(width 0)
					(fill yes)
				)
			)
		)
		(pad "2" smd custom
			(at 0 0.4318 270)
			(size 0.127 0.127)
			(layers "B.Cu" "B.Mask" "B.Paste")
			(net "P3V3_STBY")
			(options
				(clearance outline)
				(anchor circle)
			)
			(primitives
				(gr_poly
					(pts
						(arc
							(start -0.2032 0.2794)
							(mid -0.239121 0.264521)
							(end -0.254 0.2286)
						)
						(arc
							(start -0.254 -0.2286)
							(mid -0.239121 -0.264521)
							(end -0.2032 -0.2794)
						)
						(arc
							(start 0.2032 -0.2794)
							(mid 0.239121 -0.264521)
							(end 0.254 -0.2286)
						)
						(arc
							(start 0.254 0.2286)
							(mid 0.239121 0.264521)
							(end 0.2032 0.2794)
						)
					)
					(width 0)
					(fill yes)
				)
			)
		)
	)
	(footprint ""
		(layer "B.Cu")
		(at 39.878 -15.9004)
		(property "Reference" "R369"
			(at 0 0 0)
			(layer "B.SilkS")
			(hide yes)
			(effects
				(font
					(size 1.27 1.27)
				)
				(justify mirror)
			)
		)
		(property "Value" "33R2F-3-GP"
			(at -0.064008 -3.993896 0)
			(unlocked yes)
			(layer "B.Fab")
			(hide yes)
			(effects
				(font
					(size 1.016 1.016)
					(thickness 0.1524)
				)
				(justify mirror)
			)
		)
		(property "Device Type" "R402H16"
			(at -0.064008 -5.517896 0)
			(unlocked yes)
			(layer "B.Fab")
			(hide yes)
			(effects
				(font
					(size 1.016 1.016)
					(thickness 0.1524)
				)
				(justify mirror)
			)
		)
		(duplicate_pad_numbers_are_jumpers no)
		(fp_rect
			(start 0.381 0.8382)
			(end -0.381 -0.8382)
			(stroke
				(width 0)
				(type default)
			)
			(fill no)
			(layer "B.CrtYd")
		)
		(fp_rect
			(start 0.381 0.8382)
			(end -0.381 -0.8382)
			(stroke
				(width 0)
				(type default)
			)
			(fill no)
			(layer "B.Fab")
		)
		(pad "1" smd custom
			(at 0 -0.4318 180)
			(size 0.127 0.127)
			(layers "B.Cu" "B.Mask" "B.Paste")
			(net "CLK_100M_CLKBUFF_SAS_R_DN")
			(options
				(clearance outline)
				(anchor circle)
			)
			(primitives
				(gr_poly
					(pts
						(arc
							(start -0.2032 0.2794)
							(mid -0.239121 0.264521)
							(end -0.254 0.2286)
						)
						(arc
							(start -0.254 -0.2286)
							(mid -0.239121 -0.264521)
							(end -0.2032 -0.2794)
						)
						(arc
							(start 0.2032 -0.2794)
							(mid 0.239121 -0.264521)
							(end 0.254 -0.2286)
						)
						(arc
							(start 0.254 0.2286)
							(mid 0.239121 0.264521)
							(end 0.2032 0.2794)
						)
					)
					(width 0)
					(fill yes)
				)
			)
		)
		(pad "2" smd custom
			(at 0 0.4318 180)
			(size 0.127 0.127)
			(layers "B.Cu" "B.Mask" "B.Paste")
			(net "CLK_100M_PCIE_SAS_DN")
			(options
				(clearance outline)
				(anchor circle)
			)
			(primitives
				(gr_poly
					(pts
						(arc
							(start -0.2032 0.2794)
							(mid -0.239121 0.264521)
							(end -0.254 0.2286)
						)
						(arc
							(start -0.254 -0.2286)
							(mid -0.239121 -0.264521)
							(end -0.2032 -0.2794)
						)
						(arc
							(start 0.2032 -0.2794)
							(mid 0.239121 -0.264521)
							(end 0.254 -0.2286)
						)
						(arc
							(start 0.254 0.2286)
							(mid 0.239121 0.264521)
							(end 0.2032 0.2794)
						)
					)
					(width 0)
					(fill yes)
				)
			)
		)
	)
)
